# BASEBOARD_FAB2 (Tioga Pass) — schematic netlist excerpt (pin names and nets, part order shuffled) for the footprints in the layout excerpt that follows; sources: Cadence DE-HDL packaged netlist, KiCad conversion of Wiwynn_Tioga_Pass_MB.brd

C4E8  SC22U16V5MX-4-GP  20%  pkg SMD-BCG5  page 214 : \1\ = VR_FET_SW_P12V_STBY_PVCCIN_CPU0 ; \2\ = GND
R7M8  RES  10.0 1% CHIP  pkg 0402  page 99 : A = SMB_DDR_KLM_SDA_G_R ; B = SMB_DDR_KLM_SDA_G
R8D7  RES  20.0 1% CHIP  pkg 0402  page 138 : A = SMB_VR_STBY_LVC3_SDA_R1 ; B = SMB_VR_STBY_LVC3_SDA

(kicad_pcb
	(version 20260206)
	(generator "pcbnew")
	(generator_version "10.0")
	(general
		(thickness 1.6)
		(legacy_teardrops no)
	)
	(paper "A4")
	(title_block
		(title "Wiwynn_Tioga_Pass_MB.brd")
		(comment 1 "Tioga Pass / footprints 4105-4107 of 4770")
	)
	(layers
		(0 "F.Cu" signal "TOP")
		(4 "In1.Cu" signal "L2GND")
		(6 "In2.Cu" signal "L3")
		(8 "In3.Cu" signal "L4GND")
		(10 "In4.Cu" signal "L5")
		(12 "In5.Cu" signal "L6GND")
		(14 "In6.Cu" signal "L7VCC")
		(16 "In7.Cu" signal "L8VCC")
		(18 "In8.Cu" signal "L9GND")
		(20 "In9.Cu" signal "L10")
		(22 "In10.Cu" signal "L11GND")
		(24 "In11.Cu" signal "L12")
		(26 "In12.Cu" signal "L13GND")
		(2 "B.Cu" signal "BOTTOM")
		(9 "F.Adhes" user "F.Adhesive")
		(11 "B.Adhes" user "B.Adhesive")
		(13 "F.Paste" user "Package Geometry/Pastemask Top")
		(15 "B.Paste" user "Package Geometry/Pastemask Bottom")
		(5 "F.SilkS" user "Ref Des/Silkscreen Top")
		(7 "B.SilkS" user "Ref Des/Silkscreen Bottom")
		(1 "F.Mask" user "Board Geometry/Soldermask Top")
		(3 "B.Mask" user "Board Geometry/Soldermask Bottom")
		(17 "Dwgs.User" user "User.Drawings")
		(19 "Cmts.User" user "User.Comments")
		(21 "Eco1.User" user "User.Eco1")
		(23 "Eco2.User" user "User.Eco2")
		(25 "Edge.Cuts" user "Board Geometry/Outline")
		(27 "Margin" user)
		(31 "F.CrtYd" user "Package Geometry/Place Bound Top")
		(29 "B.CrtYd" user "Package Geometry/Place Bound Bottom")
		(35 "F.Fab" user "Ref Des/Assembly Top")
		(33 "B.Fab" user "Ref Des/Assembly Bottom")
	)
	(footprint ""
		(layer "B.Cu")
		(at 156.19222 -121.4247 180)
		(property "Reference" "R7M8"
			(at 0 0 0)
			(layer "B.SilkS")
			(hide yes)
			(effects
				(font
					(size 1.27 1.27)
				)
				(justify mirror)
			)
		)
		(property "Value" ""
			(at 0 0 0)
			(layer "B.Fab")
			(effects
				(font
					(size 1.27 1.27)
				)
				(justify mirror)
			)
		)
		(duplicate_pad_numbers_are_jumpers no)
		(fp_poly
			(pts
				(xy 0.2794 -0.1016) (xy -0.2794 -0.1016) (xy -0.2794 0.9906) (xy 0.2794 0.9906)
			)
			(stroke
				(width 0)
				(type default)
			)
			(fill no)
			(layer "B.CrtYd")
		)
		(fp_line
			(start 0.2794 0.9906)
			(end -0.2794 0.9906)
			(stroke
				(width 0.1)
				(type default)
			)
			(layer "B.Fab")
		)
		(fp_line
			(start 0.2794 -0.1016)
			(end 0.2794 0.9906)
			(stroke
				(width 0.1)
				(type default)
			)
			(layer "B.Fab")
		)
		(fp_line
			(start -0.2794 0.9906)
			(end -0.2794 -0.1016)
			(stroke
				(width 0.1)
				(type default)
			)
			(layer "B.Fab")
		)
		(fp_line
			(start -0.2794 -0.1016)
			(end 0.2794 -0.1016)
			(stroke
				(width 0.1)
				(type default)
			)
			(layer "B.Fab")
		)
		(pad "1" smd rect
			(at 0 0)
			(size 0.508 0.508)
			(layers "B.Cu" "B.Mask" "B.Paste")
			(net "SMB_DDR_KLM_SDA_G_R")
		)
		(pad "2" smd rect
			(at 0 0.889)
			(size 0.508 0.508)
			(layers "B.Cu" "B.Mask" "B.Paste")
			(net "SMB_DDR_KLM_SDA_G")
		)
		(zone
			(layer "B.Cu")
			(hatch none 0.5)
			(connect_pads
				(clearance 0)
			)
			(min_thickness 0.25)
			(keepout
				(tracks not_allowed)
				(vias allowed)
				(pads allowed)
				(copperpour not_allowed)
				(footprints allowed)
			)
			(placement
				(enabled no)
				(sheetname "")
			)
			(fill
				(thermal_gap 0.5)
				(thermal_bridge_width 0.5)
				(island_removal_mode 0)
			)
			(polygon
				(pts
					(xy 155.93822 -122.0597) (xy 156.44622 -122.0597) (xy 156.44622 -121.6787) (xy 155.93822 -121.6787)
				)
			)
		)
		(zone
			(layer "B.Cu")
			(hatch none 0.5)
			(connect_pads
				(clearance 0)
			)
			(min_thickness 0.25)
			(keepout
				(tracks allowed)
				(vias not_allowed)
				(pads allowed)
				(copperpour not_allowed)
				(footprints allowed)
			)
			(placement
				(enabled no)
				(sheetname "")
			)
			(fill
				(thermal_gap 0.5)
				(thermal_bridge_width 0.5)
				(island_removal_mode 0)
			)
			(polygon
				(pts
					(xy 155.93822 -121.6787) (xy 156.44622 -121.6787) (xy 156.44622 -122.0597) (xy 155.93822 -122.0597)
				)
			)
		)
	)
	(footprint ""
		(layer "B.Cu")
		(at 187.071 -53.975)
		(property "Reference" "C4E8"
			(at 0 0 0)
			(layer "B.SilkS")
			(hide yes)
			(effects
				(font
					(size 1.27 1.27)
				)
				(justify mirror)
			)
		)
		(property "Value" "*"
			(at 0.0762 -6.2357 0)
			(unlocked yes)
			(layer "B.Fab")
			(hide yes)
			(effects
				(font
					(size 1.27 1.016)
					(thickness 0.1524)
				)
				(justify mirror)
			)
		)
		(property "Device Type" "SC22U16V5MX-4-GP_SMD-BCG5-SC22A"
			(at 0.0762 -8.2677 0)
			(unlocked yes)
			(layer "B.Fab")
			(hide yes)
			(effects
				(font
					(size 1.27 1.016)
					(thickness 0.1524)
				)
				(justify mirror)
			)
		)
		(duplicate_pad_numbers_are_jumpers no)
		(fp_line
			(start -0.635 0)
			(end 0.635 0)
			(stroke
				(width 0.508)
				(type default)
			)
			(layer "B.SilkS")
		)
		(fp_rect
			(start 0.9652 1.778)
			(end -0.9652 -1.778)
			(stroke
				(width 0)
				(type default)
			)
			(fill no)
			(layer "B.CrtYd")
		)
		(fp_poly
			(pts
				(xy 0.9652 -1.778) (xy -0.9652 -1.778) (xy -0.9652 1.778) (xy 0.9652 1.778)
			)
			(stroke
				(width 0)
				(type default)
			)
			(fill no)
			(layer "B.Fab")
		)
		(pad "1" smd rect
			(at 0 -0.9652 180)
			(size 1.397 1.143)
			(layers "B.Cu" "B.Mask" "B.Paste")
			(net "VR_FET_SW_P12V_STBY_PVCCIN_CPU0")
		)
		(pad "2" smd rect
			(at 0 0.9652 180)
			(size 1.397 1.143)
			(layers "B.Cu" "B.Mask" "B.Paste")
			(net "GND")
		)
	)
	(footprint ""
		(layer "B.Cu")
		(at 398.4244 -88.2777)
		(property "Reference" "R8D7"
			(at 0 0 0)
			(layer "B.SilkS")
			(hide yes)
			(effects
				(font
					(size 1.27 1.27)
				)
				(justify mirror)
			)
		)
		(property "Value" ""
			(at 0 0 0)
			(layer "B.Fab")
			(effects
				(font
					(size 1.27 1.27)
				)
				(justify mirror)
			)
		)
		(duplicate_pad_numbers_are_jumpers no)
		(fp_poly
			(pts
				(xy 0.2794 -0.1016) (xy -0.2794 -0.1016) (xy -0.2794 0.9906) (xy 0.2794 0.9906)
			)
			(stroke
				(width 0)
				(type default)
			)
			(fill no)
			(layer "B.CrtYd")
		)
		(fp_line
			(start -0.2794 -0.1016)
			(end 0.2794 -0.1016)
			(stroke
				(width 0.1)
				(type default)
			)
			(layer "B.Fab")
		)
		(fp_line
			(start -0.2794 0.9906)
			(end -0.2794 -0.1016)
			(stroke
				(width 0.1)
				(type default)
			)
			(layer "B.Fab")
		)
		(fp_line
			(start 0.2794 -0.1016)
			(end 0.2794 0.9906)
			(stroke
				(width 0.1)
				(type default)
			)
			(layer "B.Fab")
		)
		(fp_line
			(start 0.2794 0.9906)
			(end -0.2794 0.9906)
			(stroke
				(width 0.1)
				(type default)
			)
			(layer "B.Fab")
		)
		(pad "1" smd rect
			(at 0 0 180)
			(size 0.508 0.508)
			(layers "B.Cu" "B.Mask" "B.Paste")
			(net "SMB_VR_STBY_LVC3_SDA_R1")
		)
		(pad "2" smd rect
			(at 0 0.889 180)
			(size 0.508 0.508)
			(layers "B.Cu" "B.Mask" "B.Paste")
			(net "SMB_VR_STBY_LVC3_SDA")
		)
		(zone
			(layer "B.Cu")
			(hatch none 0.5)
			(connect_pads
				(clearance 0)
			)
			(min_thickness 0.25)
			(keepout
				(tracks allowed)
				(vias not_allowed)
				(pads allowed)
				(copperpour not_allowed)
				(footprints allowed)
			)
			(placement
				(enabled no)
				(sheetname "")
			)
			(fill
				(thermal_gap 0.5)
				(thermal_bridge_width 0.5)
				(island_removal_mode 0)
			)
			(polygon
				(pts
					(xy 398.6784 -88.0237) (xy 398.1704 -88.0237) (xy 398.1704 -87.6427) (xy 398.6784 -87.6427)
				)
			)
		)
		(zone
			(layer "B.Cu")
			(hatch none 0.5)
			(connect_pads
				(clearance 0)
			)
			(min_thickness 0.25)
			(keepout
				(tracks not_allowed)
				(vias allowed)
				(pads allowed)
				(copperpour not_allowed)
				(footprints allowed)
			)
			(placement
				(enabled no)
				(sheetname "")
			)
			(fill
				(thermal_gap 0.5)
				(thermal_bridge_width 0.5)
				(island_removal_mode 0)
			)
			(polygon
				(pts
					(xy 398.6784 -87.6427) (xy 398.1704 -87.6427) (xy 398.1704 -88.0237) (xy 398.6784 -88.0237)
				)
			)
		)
	)
)
